(kicad_pcb
	(version 20240108)
	(generator "pcbnew")
	(generator_version "8.0")
	(general
		(thickness 1.6)
		(legacy_teardrops no)
	)
	(paper "A4")
	(title_block
		(title "Jetson Orin Baseboard OCuLink Expansion")
		(date "2025-03-18")
		(rev "1.1.0")
		(company "Antmicro Ltd")
		(comment 1 "www.antmicro.com")
		(comment 9 "footprints 108-112 of 119")
	)
	(layers
		(0 "F.Cu" signal)
		(1 "In1.Cu" signal)
		(2 "In2.Cu" signal)
		(31 "B.Cu" signal)
		(32 "B.Adhes" user "B.Adhesive")
		(33 "F.Adhes" user "F.Adhesive")
		(34 "B.Paste" user)
		(35 "F.Paste" user)
		(36 "B.SilkS" user "B.Silkscreen")
		(37 "F.SilkS" user "F.Silkscreen")
		(38 "B.Mask" user)
		(39 "F.Mask" user)
		(40 "Dwgs.User" user "User.Drawings")
		(41 "Cmts.User" user "User.Comments")
		(42 "Eco1.User" user "User.Eco1")
		(43 "Eco2.User" user "User.Eco2")
		(44 "Edge.Cuts" user)
		(45 "Margin" user)
		(46 "B.CrtYd" user "B.Courtyard")
		(47 "F.CrtYd" user "F.Courtyard")
		(48 "B.Fab" user)
		(49 "F.Fab" user)
	)
	(footprint "antmicro-footprints:TP_SMD_1.5mm"
		(layer "B.Cu")
		(at 142.4 139.25 90)
		(property "Reference" "TP6"
			(at -8.05568 -1.3 0)
			(layer "B.SilkS")
			(hide yes)
			(effects
				(font
					(size 0.7 0.7)
					(thickness 0.15)
				)
				(justify right top mirror)
			)
		)
		(property "Value" "TP_1.5mm_SMD"
			(at 0.11744 -9.932221 0)
			(layer "B.Fab")
			(effects
				(font
					(size 0.7 0.7)
					(thickness 0.15)
				)
				(justify right top mirror)
			)
		)
		(property "Footprint" "antmicro-footprints:TP_SMD_1.5mm"
			(at 0 0 90)
			(layer "B.Fab")
			(hide yes)
			(effects
				(font
					(size 1.27 1.27)
					(thickness 0.15)
				)
				(justify mirror)
			)
		)
		(property "Description" "test point, SMT"
			(at 0 0 90)
			(layer "B.Fab")
			(hide yes)
			(effects
				(font
					(size 1.27 1.27)
					(thickness 0.15)
				)
				(justify mirror)
			)
		)
		(property "MPN" ""
			(at 0 0 -90)
			(unlocked yes)
			(layer "B.Fab")
			(hide yes)
			(effects
				(font
					(size 1 1)
					(thickness 0.15)
				)
				(justify mirror)
			)
		)
		(property "Manufacturer" ""
			(at 0 0 -90)
			(unlocked yes)
			(layer "B.Fab")
			(hide yes)
			(effects
				(font
					(size 1 1)
					(thickness 0.15)
				)
				(justify mirror)
			)
		)
		(property "Author" "Antmicro"
			(at 0 0 -90)
			(unlocked yes)
			(layer "B.Fab")
			(hide yes)
			(effects
				(font
					(size 1 1)
					(thickness 0.15)
				)
				(justify mirror)
			)
		)
		(property "License" "Apache-2.0"
			(at 0 0 -90)
			(unlocked yes)
			(layer "B.Fab")
			(hide yes)
			(effects
				(font
					(size 1 1)
					(thickness 0.15)
				)
				(justify mirror)
			)
		)
		(sheetname "Root")
		(sheetfile "jetson-orin-baseboard-oculink-expansion.kicad_sch")
		(attr exclude_from_pos_files exclude_from_bom)
		(fp_circle
			(center 0 0)
			(end 0.85 0)
			(stroke
				(width 0.05)
				(type default)
			)
			(fill none)
			(layer "B.CrtYd")
		)
		(fp_text user "License: Apache-2.0"
			(at -0.7 -5.301 90)
			(layer "B.Fab")
			(hide yes)
			(effects
				(font
					(size 0.7 0.7)
					(thickness 0.15)
				)
				(justify right top mirror)
			)
		)
		(fp_text user "${REFERENCE}"
			(at -0.7 -2.9 90)
			(layer "B.Fab")
			(hide yes)
			(effects
				(font
					(size 0.7 0.7)
					(thickness 0.15)
				)
				(justify right top mirror)
			)
		)
		(fp_text user "Author: Antmicro"
			(at -0.7 -4.101 90)
			(layer "B.Fab")
			(hide yes)
			(effects
				(font
					(size 0.7 0.7)
					(thickness 0.15)
				)
				(justify right top mirror)
			)
		)
		(pad "1" smd circle
			(at 0 0 180)
			(size 1.5 1.5)
			(layers "B.Cu" "B.Mask")
			(net 65 "/JOB_GPIO09")
			(pinfunction "1")
			(pintype "passive")
		)
	)
	(footprint "antmicro-footprints:R_0402_1005Metric"
		(layer "B.Cu")
		(at 118.325 111.093751 180)
		(descr "Resistor SMD 0402")
		(tags "resistor SMD 0402")
		(property "Reference" "R10"
			(at -3.255 -0.47725 0)
			(layer "B.SilkS")
			(effects
				(font
					(size 0.7 0.7)
					(thickness 0.15)
				)
				(justify left bottom mirror)
			)
		)
		(property "Value" "R_1k_0402"
			(at -1.011843 -1.772047 0)
			(layer "B.Fab")
			(effects
				(font
					(size 0.7 0.7)
					(thickness 0.15)
				)
				(justify left bottom mirror)
			)
		)
		(property "Footprint" "antmicro-footprints:R_0402_1005Metric"
			(at 0 0 0)
			(layer "B.Fab")
			(hide yes)
			(effects
				(font
					(size 1.27 1.27)
					(thickness 0.15)
				)
				(justify mirror)
			)
		)
		(property "Datasheet" "https://www.bourns.com/docs/product-datasheets/cr.pdf"
			(at 0 0 0)
			(layer "B.Fab")
			(hide yes)
			(effects
				(font
					(size 1.27 1.27)
					(thickness 0.15)
				)
				(justify mirror)
			)
		)
		(property "Description" "SMD Chip Resistor, 1 kohm, ± 1%, 63 mW, 0402 [1005 Metric], Thick Film, General Purpose"
			(at 0 0 0)
			(layer "B.Fab")
			(hide yes)
			(effects
				(font
					(size 1.27 1.27)
					(thickness 0.15)
				)
				(justify mirror)
			)
		)
		(property "MPN" "CR0402-FX-1001GLF"
			(at 0 0 0)
			(unlocked yes)
			(layer "B.Fab")
			(hide yes)
			(effects
				(font
					(size 1 1)
					(thickness 0.15)
				)
				(justify mirror)
			)
		)
		(property "Manufacturer" "Bourns"
			(at 0 0 0)
			(unlocked yes)
			(layer "B.Fab")
			(hide yes)
			(effects
				(font
					(size 1 1)
					(thickness 0.15)
				)
				(justify mirror)
			)
		)
		(property "License" "Apache-2.0"
			(at 0 0 0)
			(unlocked yes)
			(layer "B.Fab")
			(hide yes)
			(effects
				(font
					(size 1 1)
					(thickness 0.15)
				)
				(justify mirror)
			)
		)
		(property "Author" "Antmicro"
			(at 0 0 0)
			(unlocked yes)
			(layer "B.Fab")
			(hide yes)
			(effects
				(font
					(size 1 1)
					(thickness 0.15)
				)
				(justify mirror)
			)
		)
		(property "Val" "1k"
			(at 0 0 0)
			(unlocked yes)
			(layer "B.Fab")
			(hide yes)
			(effects
				(font
					(size 1 1)
					(thickness 0.15)
				)
				(justify mirror)
			)
		)
		(property "Tolerance" "1%"
			(at 0 0 0)
			(unlocked yes)
			(layer "B.Fab")
			(hide yes)
			(effects
				(font
					(size 1 1)
					(thickness 0.15)
				)
				(justify mirror)
			)
		)
		(property "Public" "False"
			(at 0 0 0)
			(unlocked yes)
			(layer "B.Fab")
			(hide yes)
			(effects
				(font
					(size 1 1)
					(thickness 0.15)
				)
				(justify mirror)
			)
		)
		(sheetname "Root")
		(sheetfile "jetson-orin-baseboard-oculink-expansion.kicad_sch")
		(attr smd dnp)
		(fp_rect
			(start -0.925 0.47)
			(end 0.925 -0.47)
			(stroke
				(width 0.05)
				(type default)
			)
			(fill none)
			(layer "B.CrtYd")
		)
		(fp_rect
			(start -0.5 0.25)
			(end 0.5 -0.25)
			(stroke
				(width 0.15)
				(type solid)
			)
			(fill none)
			(layer "B.Fab")
		)
		(fp_text user "Author: Antmicro"
			(at -0.95 -4.169 0)
			(layer "B.Fab")
			(hide yes)
			(effects
				(font
					(size 0.7 0.7)
					(thickness 0.15)
				)
				(justify left bottom mirror)
			)
		)
		(fp_text user "${REFERENCE}"
			(at -0.95 -3.168 0)
			(layer "B.Fab")
			(hide yes)
			(effects
				(font
					(size 0.7 0.7)
					(thickness 0.15)
				)
				(justify left bottom mirror)
			)
		)
		(fp_text user "License: Apache-2.0"
			(at -0.95 -5.169 0)
			(layer "B.Fab")
			(hide yes)
			(effects
				(font
					(size 0.7 0.7)
					(thickness 0.15)
				)
				(justify left bottom mirror)
			)
		)
		(pad "1" smd roundrect
			(at -0.48 0 180)
			(size 0.59 0.64)
			(layers "B.Cu" "B.Paste" "B.Mask")
			(roundrect_rratio 0.25)
			(net 23 "+3V3")
			(pintype "passive")
		)
		(pad "2" smd roundrect
			(at 0.48 0 180)
			(size 0.59 0.64)
			(layers "B.Cu" "B.Paste" "B.Mask")
			(roundrect_rratio 0.25)
			(net 92 "/RX_FG0")
			(pintype "passive")
		)
	)
	(footprint "antmicro-footprints:R_0402_1005Metric"
		(layer "B.Cu")
		(at 116.475 115.313751)
		(descr "Resistor SMD 0402")
		(tags "resistor SMD 0402")
		(property "Reference" "R7"
			(at -2.585 -0.383751 0)
			(layer "B.SilkS")
			(effects
				(font
					(size 0.7 0.7)
					(thickness 0.15)
				)
				(justify right top mirror)
			)
		)
		(property "Value" "R_1k_0402"
			(at -1.011843 -1.772047 0)
			(layer "B.Fab")
			(effects
				(font
					(size 0.7 0.7)
					(thickness 0.15)
				)
				(justify right top mirror)
			)
		)
		(property "Footprint" "antmicro-footprints:R_0402_1005Metric"
			(at 0 0 0)
			(layer "B.Fab")
			(hide yes)
			(effects
				(font
					(size 1.27 1.27)
					(thickness 0.15)
				)
				(justify mirror)
			)
		)
		(property "Datasheet" "https://www.bourns.com/docs/product-datasheets/cr.pdf"
			(at 0 0 0)
			(layer "B.Fab")
			(hide yes)
			(effects
				(font
					(size 1.27 1.27)
					(thickness 0.15)
				)
				(justify mirror)
			)
		)
		(property "Description" "SMD Chip Resistor, 1 kohm, ± 1%, 63 mW, 0402 [1005 Metric], Thick Film, General Purpose"
			(at 0 0 0)
			(layer "B.Fab")
			(hide yes)
			(effects
				(font
					(size 1.27 1.27)
					(thickness 0.15)
				)
				(justify mirror)
			)
		)
		(property "MPN" "CR0402-FX-1001GLF"
			(at 0 0 180)
			(unlocked yes)
			(layer "B.Fab")
			(hide yes)
			(effects
				(font
					(size 1 1)
					(thickness 0.15)
				)
				(justify mirror)
			)
		)
		(property "Manufacturer" "Bourns"
			(at 0 0 180)
			(unlocked yes)
			(layer "B.Fab")
			(hide yes)
			(effects
				(font
					(size 1 1)
					(thickness 0.15)
				)
				(justify mirror)
			)
		)
		(property "License" "Apache-2.0"
			(at 0 0 180)
			(unlocked yes)
			(layer "B.Fab")
			(hide yes)
			(effects
				(font
					(size 1 1)
					(thickness 0.15)
				)
				(justify mirror)
			)
		)
		(property "Author" "Antmicro"
			(at 0 0 180)
			(unlocked yes)
			(layer "B.Fab")
			(hide yes)
			(effects
				(font
					(size 1 1)
					(thickness 0.15)
				)
				(justify mirror)
			)
		)
		(property "Val" "1k"
			(at 0 0 180)
			(unlocked yes)
			(layer "B.Fab")
			(hide yes)
			(effects
				(font
					(size 1 1)
					(thickness 0.15)
				)
				(justify mirror)
			)
		)
		(property "Tolerance" "1%"
			(at 0 0 180)
			(unlocked yes)
			(layer "B.Fab")
			(hide yes)
			(effects
				(font
					(size 1 1)
					(thickness 0.15)
				)
				(justify mirror)
			)
		)
		(property "Public" "False"
			(at 0 0 180)
			(unlocked yes)
			(layer "B.Fab")
			(hide yes)
			(effects
				(font
					(size 1 1)
					(thickness 0.15)
				)
				(justify mirror)
			)
		)
		(sheetname "Root")
		(sheetfile "jetson-orin-baseboard-oculink-expansion.kicad_sch")
		(attr smd dnp)
		(fp_rect
			(start -0.925 0.47)
			(end 0.925 -0.47)
			(stroke
				(width 0.05)
				(type default)
			)
			(fill none)
			(layer "B.CrtYd")
		)
		(fp_rect
			(start -0.5 0.25)
			(end 0.5 -0.25)
			(stroke
				(width 0.15)
				(type solid)
			)
			(fill none)
			(layer "B.Fab")
		)
		(fp_text user "Author: Antmicro"
			(at -0.95 -4.169 0)
			(layer "B.Fab")
			(hide yes)
			(effects
				(font
					(size 0.7 0.7)
					(thickness 0.15)
				)
				(justify right top mirror)
			)
		)
		(fp_text user "License: Apache-2.0"
			(at -0.95 -5.169 0)
			(layer "B.Fab")
			(hide yes)
			(effects
				(font
					(size 0.7 0.7)
					(thickness 0.15)
				)
				(justify right top mirror)
			)
		)
		(fp_text user "${REFERENCE}"
			(at -0.95 -3.168 0)
			(layer "B.Fab")
			(hide yes)
			(effects
				(font
					(size 0.7 0.7)
					(thickness 0.15)
				)
				(justify right top mirror)
			)
		)
		(pad "1" smd roundrect
			(at -0.48 0)
			(size 0.59 0.64)
			(layers "B.Cu" "B.Paste" "B.Mask")
			(roundrect_rratio 0.25)
			(net 51 "GND")
			(pintype "passive")
		)
		(pad "2" smd roundrect
			(at 0.48 0)
			(size 0.59 0.64)
			(layers "B.Cu" "B.Paste" "B.Mask")
			(roundrect_rratio 0.25)
			(net 90 "/RX_EQ1")
			(pintype "passive")
		)
	)
	(footprint "antmicro-footprints:R_0402_1005Metric"
		(layer "B.Cu")
		(at 116.475 116.653751)
		(descr "Resistor SMD 0402")
		(tags "resistor SMD 0402")
		(property "Reference" "R9"
			(at -2.585 -0.383751 0)
			(layer "B.SilkS")
			(effects
				(font
					(size 0.7 0.7)
					(thickness 0.15)
				)
				(justify right top mirror)
			)
		)
		(property "Value" "R_1k_0402"
			(at -1.011843 -1.772047 0)
			(layer "B.Fab")
			(effects
				(font
					(size 0.7 0.7)
					(thickness 0.15)
				)
				(justify right top mirror)
			)
		)
		(property "Footprint" "antmicro-footprints:R_0402_1005Metric"
			(at 0 0 0)
			(layer "B.Fab")
			(hide yes)
			(effects
				(font
					(size 1.27 1.27)
					(thickness 0.15)
				)
				(justify mirror)
			)
		)
		(property "Datasheet" "https://www.bourns.com/docs/product-datasheets/cr.pdf"
			(at 0 0 0)
			(layer "B.Fab")
			(hide yes)
			(effects
				(font
					(size 1.27 1.27)
					(thickness 0.15)
				)
				(justify mirror)
			)
		)
		(property "Description" "SMD Chip Resistor, 1 kohm, ± 1%, 63 mW, 0402 [1005 Metric], Thick Film, General Purpose"
			(at 0 0 0)
			(layer "B.Fab")
			(hide yes)
			(effects
				(font
					(size 1.27 1.27)
					(thickness 0.15)
				)
				(justify mirror)
			)
		)
		(property "MPN" "CR0402-FX-1001GLF"
			(at 0 0 180)
			(unlocked yes)
			(layer "B.Fab")
			(hide yes)
			(effects
				(font
					(size 1 1)
					(thickness 0.15)
				)
				(justify mirror)
			)
		)
		(property "Manufacturer" "Bourns"
			(at 0 0 180)
			(unlocked yes)
			(layer "B.Fab")
			(hide yes)
			(effects
				(font
					(size 1 1)
					(thickness 0.15)
				)
				(justify mirror)
			)
		)
		(property "License" "Apache-2.0"
			(at 0 0 180)
			(unlocked yes)
			(layer "B.Fab")
			(hide yes)
			(effects
				(font
					(size 1 1)
					(thickness 0.15)
				)
				(justify mirror)
			)
		)
		(property "Author" "Antmicro"
			(at 0 0 180)
			(unlocked yes)
			(layer "B.Fab")
			(hide yes)
			(effects
				(font
					(size 1 1)
					(thickness 0.15)
				)
				(justify mirror)
			)
		)
		(property "Val" "1k"
			(at 0 0 180)
			(unlocked yes)
			(layer "B.Fab")
			(hide yes)
			(effects
				(font
					(size 1 1)
					(thickness 0.15)
				)
				(justify mirror)
			)
		)
		(property "Tolerance" "1%"
			(at 0 0 180)
			(unlocked yes)
			(layer "B.Fab")
			(hide yes)
			(effects
				(font
					(size 1 1)
					(thickness 0.15)
				)
				(justify mirror)
			)
		)
		(property "Public" "False"
			(at 0 0 180)
			(unlocked yes)
			(layer "B.Fab")
			(hide yes)
			(effects
				(font
					(size 1 1)
					(thickness 0.15)
				)
				(justify mirror)
			)
		)
		(sheetname "Root")
		(sheetfile "jetson-orin-baseboard-oculink-expansion.kicad_sch")
		(attr smd dnp)
		(fp_rect
			(start -0.925 0.47)
			(end 0.925 -0.47)
			(stroke
				(width 0.05)
				(type default)
			)
			(fill none)
			(layer "B.CrtYd")
		)
		(fp_rect
			(start -0.5 0.25)
			(end 0.5 -0.25)
			(stroke
				(width 0.15)
				(type solid)
			)
			(fill none)
			(layer "B.Fab")
		)
		(fp_text user "License: Apache-2.0"
			(at -0.95 -5.169 0)
			(layer "B.Fab")
			(hide yes)
			(effects
				(font
					(size 0.7 0.7)
					(thickness 0.15)
				)
				(justify right top mirror)
			)
		)
		(fp_text user "Author: Antmicro"
			(at -0.95 -4.169 0)
			(layer "B.Fab")
			(hide yes)
			(effects
				(font
					(size 0.7 0.7)
					(thickness 0.15)
				)
				(justify right top mirror)
			)
		)
		(fp_text user "${REFERENCE}"
			(at -0.95 -3.168 0)
			(layer "B.Fab")
			(hide yes)
			(effects
				(font
					(size 0.7 0.7)
					(thickness 0.15)
				)
				(justify right top mirror)
			)
		)
		(pad "1" smd roundrect
			(at -0.48 0)
			(size 0.59 0.64)
			(layers "B.Cu" "B.Paste" "B.Mask")
			(roundrect_rratio 0.25)
			(net 51 "GND")
			(pintype "passive")
		)
		(pad "2" smd roundrect
			(at 0.48 0)
			(size 0.59 0.64)
			(layers "B.Cu" "B.Paste" "B.Mask")
			(roundrect_rratio 0.25)
			(net 91 "/RX_EQ2")
			(pintype "passive")
		)
	)
	(footprint "antmicro-footprints:R_0402_1005Metric"
		(layer "B.Cu")
		(at 118.325 115.313751 180)
		(descr "Resistor SMD 0402")
		(tags "resistor SMD 0402")
		(property "Reference" "R6"
			(at -2.588333 -0.47725 0)
			(layer "B.SilkS")
			(effects
				(font
					(size 0.7 0.7)
					(thickness 0.15)
				)
				(justify left bottom mirror)
			)
		)
		(property "Value" "R_1k_0402"
			(at -1.011843 -1.772047 0)
			(layer "B.Fab")
			(effects
				(font
					(size 0.7 0.7)
					(thickness 0.15)
				)
				(justify left bottom mirror)
			)
		)
		(property "Footprint" "antmicro-footprints:R_0402_1005Metric"
			(at 0 0 0)
			(layer "B.Fab")
			(hide yes)
			(effects
				(font
					(size 1.27 1.27)
					(thickness 0.15)
				)
				(justify mirror)
			)
		)
		(property "Datasheet" "https://www.bourns.com/docs/product-datasheets/cr.pdf"
			(at 0 0 0)
			(layer "B.Fab")
			(hide yes)
			(effects
				(font
					(size 1.27 1.27)
					(thickness 0.15)
				)
				(justify mirror)
			)
		)
		(property "Description" "SMD Chip Resistor, 1 kohm, ± 1%, 63 mW, 0402 [1005 Metric], Thick Film, General Purpose"
			(at 0 0 0)
			(layer "B.Fab")
			(hide yes)
			(effects
				(font
					(size 1.27 1.27)
					(thickness 0.15)
				)
				(justify mirror)
			)
		)
		(property "MPN" "CR0402-FX-1001GLF"
			(at 0 0 0)
			(unlocked yes)
			(layer "B.Fab")
			(hide yes)
			(effects
				(font
					(size 1 1)
					(thickness 0.15)
				)
				(justify mirror)
			)
		)
		(property "Manufacturer" "Bourns"
			(at 0 0 0)
			(unlocked yes)
			(layer "B.Fab")
			(hide yes)
			(effects
				(font
					(size 1 1)
					(thickness 0.15)
				)
				(justify mirror)
			)
		)
		(property "License" "Apache-2.0"
			(at 0 0 0)
			(unlocked yes)
			(layer "B.Fab")
			(hide yes)
			(effects
				(font
					(size 1 1)
					(thickness 0.15)
				)
				(justify mirror)
			)
		)
		(property "Author" "Antmicro"
			(at 0 0 0)
			(unlocked yes)
			(layer "B.Fab")
			(hide yes)
			(effects
				(font
					(size 1 1)
					(thickness 0.15)
				)
				(justify mirror)
			)
		)
		(property "Val" "1k"
			(at 0 0 0)
			(unlocked yes)
			(layer "B.Fab")
			(hide yes)
			(effects
				(font
					(size 1 1)
					(thickness 0.15)
				)
				(justify mirror)
			)
		)
		(property "Tolerance" "1%"
			(at 0 0 0)
			(unlocked yes)
			(layer "B.Fab")
			(hide yes)
			(effects
				(font
					(size 1 1)
					(thickness 0.15)
				)
				(justify mirror)
			)
		)
		(property "Public" "False"
			(at 0 0 0)
			(unlocked yes)
			(layer "B.Fab")
			(hide yes)
			(effects
				(font
					(size 1 1)
					(thickness 0.15)
				)
				(justify mirror)
			)
		)
		(sheetname "Root")
		(sheetfile "jetson-orin-baseboard-oculink-expansion.kicad_sch")
		(attr smd)
		(fp_rect
			(start -0.925 0.47)
			(end 0.925 -0.47)
			(stroke
				(width 0.05)
				(type default)
			)
			(fill none)
			(layer "B.CrtYd")
		)
		(fp_rect
			(start -0.5 0.25)
			(end 0.5 -0.25)
			(stroke
				(width 0.15)
				(type solid)
			)
			(fill none)
			(layer "B.Fab")
		)
		(fp_text user "${REFERENCE}"
			(at -0.95 -3.168 0)
			(layer "B.Fab")
			(hide yes)
			(effects
				(font
					(size 0.7 0.7)
					(thickness 0.15)
				)
				(justify left bottom mirror)
			)
		)
		(fp_text user "License: Apache-2.0"
			(at -0.95 -5.169 0)
			(layer "B.Fab")
			(hide yes)
			(effects
				(font
					(size 0.7 0.7)
					(thickness 0.15)
				)
				(justify left bottom mirror)
			)
		)
		(fp_text user "Author: Antmicro"
			(at -0.95 -4.169 0)
			(layer "B.Fab")
			(hide yes)
			(effects
				(font
					(size 0.7 0.7)
					(thickness 0.15)
				)
				(justify left bottom mirror)
			)
		)
		(pad "1" smd roundrect
			(at -0.48 0 180)
			(size 0.59 0.64)
			(layers "B.Cu" "B.Paste" "B.Mask")
			(roundrect_rratio 0.25)
			(net 23 "+3V3")
			(pintype "passive")
		)
		(pad "2" smd roundrect
			(at 0.48 0 180)
			(size 0.59 0.64)
			(layers "B.Cu" "B.Paste" "B.Mask")
			(roundrect_rratio 0.25)
			(net 90 "/RX_EQ1")
			(pintype "passive")
		)
	)
)
